(kicad_pcb
	(version 20260206)
	(generator "pcbnew")
	(generator_version "10.0")
	(general
		(thickness 1.6)
		(legacy_teardrops no)
	)
	(paper "A4")
	(title_block
		(title "01162023_DA0F0TEBIF0_F0T_Expander_BD_F_brd_V02_OCP.brd")
		(comment 1 "Grand Teton / footprints 6470-6476 of 9728")
	)
	(layers
		(0 "F.Cu" signal "TOP")
		(4 "In1.Cu" signal "GND")
		(6 "In2.Cu" signal "VCC")
		(8 "In3.Cu" signal "VCC1")
		(10 "In4.Cu" signal "GND1")
		(12 "In5.Cu" signal "IN1")
		(14 "In6.Cu" signal "GND2")
		(16 "In7.Cu" signal "IN2")
		(18 "In8.Cu" signal "GND3")
		(20 "In9.Cu" signal "IN3")
		(22 "In10.Cu" signal "GND4")
		(24 "In11.Cu" signal "IN4")
		(26 "In12.Cu" signal "GND5")
		(28 "In13.Cu" signal "IN5")
		(30 "In14.Cu" signal "GND6")
		(32 "In15.Cu" signal "IN6")
		(34 "In16.Cu" signal "GND7")
		(2 "B.Cu" signal "BOTTOM")
		(9 "F.Adhes" user "F.Adhesive")
		(11 "B.Adhes" user "B.Adhesive")
		(13 "F.Paste" user "Package Geometry/Pastemask Top")
		(15 "B.Paste" user "Package Geometry/Pastemask Bottom")
		(5 "F.SilkS" user "Ref Des/Silkscreen Top")
		(7 "B.SilkS" user "Ref Des/Silkscreen Bottom")
		(1 "F.Mask" user "Board Geometry/Soldermask Top")
		(3 "B.Mask" user "Board Geometry/Soldermask Bottom")
		(17 "Dwgs.User" user "User.Drawings")
		(19 "Cmts.User" user "User.Comments")
		(21 "Eco1.User" user "User.Eco1")
		(23 "Eco2.User" user "User.Eco2")
		(25 "Edge.Cuts" user "Board Geometry/Outline")
		(27 "Margin" user)
		(31 "F.CrtYd" user "Package Geometry/Place Bound Top")
		(29 "B.CrtYd" user "Package Geometry/Place Bound Bottom")
		(35 "F.Fab" user "Ref Des/Assembly Top")
		(33 "B.Fab" user "Ref Des/Assembly Bottom")
	)
	(footprint ""
		(layer "F.Cu")
		(at 310.443626 -45.88891)
		(property "Reference" "R620"
			(at 0 0 0)
			(layer "F.SilkS")
			(hide yes)
			(effects
				(font
					(size 1.27 1.27)
				)
			)
		)
		(property "Value" ""
			(at 0 0 0)
			(layer "F.Fab")
			(effects
				(font
					(size 1.27 1.27)
				)
			)
		)
		(duplicate_pad_numbers_are_jumpers no)
		(fp_line
			(start -0.7874 -0.4064)
			(end 0.7874 -0.4064)
			(stroke
				(width 0.1524)
				(type default)
			)
			(layer "F.SilkS")
		)
		(fp_line
			(start -0.7874 0.4064)
			(end -0.7874 -0.4064)
			(stroke
				(width 0.1524)
				(type default)
			)
			(layer "F.SilkS")
		)
		(fp_line
			(start 0.7874 -0.4064)
			(end 0.7874 0.4064)
			(stroke
				(width 0.1524)
				(type default)
			)
			(layer "F.SilkS")
		)
		(fp_line
			(start 0.7874 0.4064)
			(end -0.7874 0.4064)
			(stroke
				(width 0.1524)
				(type default)
			)
			(layer "F.SilkS")
		)
		(fp_line
			(start -0.67945 -0.305054)
			(end -0.12065 -0.305054)
			(stroke
				(width 0.1)
				(type default)
			)
			(layer "F.Fab")
		)
		(fp_line
			(start -0.67945 0.3048)
			(end -0.67945 -0.305054)
			(stroke
				(width 0.1)
				(type default)
			)
			(layer "F.Fab")
		)
		(fp_line
			(start -0.12065 -0.305054)
			(end -0.12065 -0.2794)
			(stroke
				(width 0.1)
				(type default)
			)
			(layer "F.Fab")
		)
		(fp_line
			(start -0.12065 -0.2794)
			(end 0.12065 -0.2794)
			(stroke
				(width 0.1)
				(type default)
			)
			(layer "F.Fab")
		)
		(fp_line
			(start -0.12065 0.2794)
			(end -0.12065 0.3048)
			(stroke
				(width 0.1)
				(type default)
			)
			(layer "F.Fab")
		)
		(fp_line
			(start -0.12065 0.3048)
			(end -0.67945 0.3048)
			(stroke
				(width 0.1)
				(type default)
			)
			(layer "F.Fab")
		)
		(fp_line
			(start 0.120396 0.2794)
			(end -0.12065 0.2794)
			(stroke
				(width 0.1)
				(type default)
			)
			(layer "F.Fab")
		)
		(fp_line
			(start 0.120396 0.3048)
			(end 0.120396 0.2794)
			(stroke
				(width 0.1)
				(type default)
			)
			(layer "F.Fab")
		)
		(fp_line
			(start 0.12065 -0.3048)
			(end 0.67945 -0.3048)
			(stroke
				(width 0.1)
				(type default)
			)
			(layer "F.Fab")
		)
		(fp_line
			(start 0.12065 -0.2794)
			(end 0.12065 -0.3048)
			(stroke
				(width 0.1)
				(type default)
			)
			(layer "F.Fab")
		)
		(fp_line
			(start 0.67945 -0.3048)
			(end 0.67945 0.3048)
			(stroke
				(width 0.1)
				(type default)
			)
			(layer "F.Fab")
		)
		(fp_line
			(start 0.67945 0.3048)
			(end 0.120396 0.3048)
			(stroke
				(width 0.1)
				(type default)
			)
			(layer "F.Fab")
		)
		(pad "1" smd circle
			(at -0.40005 0)
			(size 0 0)
			(layers "F.Cu" "F.Mask" "F.Paste")
			(net "SSD10_ADC_A0")
		)
		(pad "2" smd circle
			(at 0.40005 0)
			(size 0 0)
			(layers "F.Cu" "F.Mask" "F.Paste")
			(net "GND")
		)
	)
	(footprint ""
		(layer "F.Cu")
		(at 28.341828 -27.006296 -90)
		(property "Reference" "PR6922"
			(at 0 0 270)
			(layer "F.SilkS")
			(hide yes)
			(effects
				(font
					(size 1.27 1.27)
				)
			)
		)
		(property "Value" ""
			(at 0 0 270)
			(layer "F.Fab")
			(effects
				(font
					(size 1.27 1.27)
				)
			)
		)
		(duplicate_pad_numbers_are_jumpers no)
		(fp_line
			(start -0.7874 0.4064)
			(end -0.7874 -0.4064)
			(stroke
				(width 0.1524)
				(type default)
			)
			(layer "F.SilkS")
		)
		(fp_line
			(start 0.7874 0.4064)
			(end -0.7874 0.4064)
			(stroke
				(width 0.1524)
				(type default)
			)
			(layer "F.SilkS")
		)
		(fp_line
			(start -0.7874 -0.4064)
			(end 0.7874 -0.4064)
			(stroke
				(width 0.1524)
				(type default)
			)
			(layer "F.SilkS")
		)
		(fp_line
			(start 0.7874 -0.4064)
			(end 0.7874 0.4064)
			(stroke
				(width 0.1524)
				(type default)
			)
			(layer "F.SilkS")
		)
		(fp_line
			(start -0.67945 0.3048)
			(end -0.67945 -0.305054)
			(stroke
				(width 0.1)
				(type default)
			)
			(layer "F.Fab")
		)
		(fp_line
			(start -0.12065 0.3048)
			(end -0.67945 0.3048)
			(stroke
				(width 0.1)
				(type default)
			)
			(layer "F.Fab")
		)
		(fp_line
			(start 0.120396 0.3048)
			(end 0.120396 0.2794)
			(stroke
				(width 0.1)
				(type default)
			)
			(layer "F.Fab")
		)
		(fp_line
			(start 0.67945 0.3048)
			(end 0.120396 0.3048)
			(stroke
				(width 0.1)
				(type default)
			)
			(layer "F.Fab")
		)
		(fp_line
			(start -0.12065 0.2794)
			(end -0.12065 0.3048)
			(stroke
				(width 0.1)
				(type default)
			)
			(layer "F.Fab")
		)
		(fp_line
			(start 0.120396 0.2794)
			(end -0.12065 0.2794)
			(stroke
				(width 0.1)
				(type default)
			)
			(layer "F.Fab")
		)
		(fp_line
			(start -0.12065 -0.2794)
			(end 0.12065 -0.2794)
			(stroke
				(width 0.1)
				(type default)
			)
			(layer "F.Fab")
		)
		(fp_line
			(start 0.12065 -0.2794)
			(end 0.12065 -0.3048)
			(stroke
				(width 0.1)
				(type default)
			)
			(layer "F.Fab")
		)
		(fp_line
			(start 0.12065 -0.3048)
			(end 0.67945 -0.3048)
			(stroke
				(width 0.1)
				(type default)
			)
			(layer "F.Fab")
		)
		(fp_line
			(start 0.67945 -0.3048)
			(end 0.67945 0.3048)
			(stroke
				(width 0.1)
				(type default)
			)
			(layer "F.Fab")
		)
		(fp_line
			(start -0.67945 -0.305054)
			(end -0.12065 -0.305054)
			(stroke
				(width 0.1)
				(type default)
			)
			(layer "F.Fab")
		)
		(fp_line
			(start -0.12065 -0.305054)
			(end -0.12065 -0.2794)
			(stroke
				(width 0.1)
				(type default)
			)
			(layer "F.Fab")
		)
		(pad "1" smd circle
			(at -0.40005 0 270)
			(size 0 0)
			(layers "F.Cu" "F.Mask" "F.Paste")
			(net "P3V3_SSD1_CO_ILIMIT")
		)
		(pad "2" smd circle
			(at 0.40005 0 270)
			(size 0 0)
			(layers "F.Cu" "F.Mask" "F.Paste")
			(net "GND")
		)
	)
	(footprint ""
		(layer "F.Cu")
		(at 317.27521 -388.960868)
		(property "Reference" "C4112"
			(at 0 0 0)
			(layer "F.SilkS")
			(hide yes)
			(effects
				(font
					(size 1.27 1.27)
				)
			)
		)
		(property "Value" ""
			(at 0 0 0)
			(layer "F.Fab")
			(effects
				(font
					(size 1.27 1.27)
				)
			)
		)
		(duplicate_pad_numbers_are_jumpers no)
		(fp_line
			(start -0.7874 -0.4064)
			(end 0.7874 -0.4064)
			(stroke
				(width 0.1524)
				(type default)
			)
			(layer "F.SilkS")
		)
		(fp_line
			(start -0.7874 0.4064)
			(end -0.7874 -0.4064)
			(stroke
				(width 0.1524)
				(type default)
			)
			(layer "F.SilkS")
		)
		(fp_line
			(start 0.7874 -0.4064)
			(end 0.7874 0.4064)
			(stroke
				(width 0.1524)
				(type default)
			)
			(layer "F.SilkS")
		)
		(fp_line
			(start 0.7874 0.4064)
			(end -0.7874 0.4064)
			(stroke
				(width 0.1524)
				(type default)
			)
			(layer "F.SilkS")
		)
		(fp_line
			(start -0.67945 -0.305054)
			(end -0.12065 -0.305054)
			(stroke
				(width 0.1)
				(type default)
			)
			(layer "F.Fab")
		)
		(fp_line
			(start -0.67945 0.3048)
			(end -0.67945 -0.305054)
			(stroke
				(width 0.1)
				(type default)
			)
			(layer "F.Fab")
		)
		(fp_line
			(start -0.12065 -0.305054)
			(end -0.12065 -0.2794)
			(stroke
				(width 0.1)
				(type default)
			)
			(layer "F.Fab")
		)
		(fp_line
			(start -0.12065 -0.2794)
			(end 0.12065 -0.2794)
			(stroke
				(width 0.1)
				(type default)
			)
			(layer "F.Fab")
		)
		(fp_line
			(start -0.12065 0.2794)
			(end -0.12065 0.3048)
			(stroke
				(width 0.1)
				(type default)
			)
			(layer "F.Fab")
		)
		(fp_line
			(start -0.12065 0.3048)
			(end -0.67945 0.3048)
			(stroke
				(width 0.1)
				(type default)
			)
			(layer "F.Fab")
		)
		(fp_line
			(start 0.120396 0.2794)
			(end -0.12065 0.2794)
			(stroke
				(width 0.1)
				(type default)
			)
			(layer "F.Fab")
		)
		(fp_line
			(start 0.120396 0.3048)
			(end 0.120396 0.2794)
			(stroke
				(width 0.1)
				(type default)
			)
			(layer "F.Fab")
		)
		(fp_line
			(start 0.12065 -0.3048)
			(end 0.67945 -0.3048)
			(stroke
				(width 0.1)
				(type default)
			)
			(layer "F.Fab")
		)
		(fp_line
			(start 0.12065 -0.2794)
			(end 0.12065 -0.3048)
			(stroke
				(width 0.1)
				(type default)
			)
			(layer "F.Fab")
		)
		(fp_line
			(start 0.67945 -0.3048)
			(end 0.67945 0.3048)
			(stroke
				(width 0.1)
				(type default)
			)
			(layer "F.Fab")
		)
		(fp_line
			(start 0.67945 0.3048)
			(end 0.120396 0.3048)
			(stroke
				(width 0.1)
				(type default)
			)
			(layer "F.Fab")
		)
		(pad "1" smd circle
			(at -0.40005 0)
			(size 0 0)
			(layers "F.Cu" "F.Mask" "F.Paste")
			(net "GND")
		)
		(pad "2" smd circle
			(at 0.40005 0)
			(size 0 0)
			(layers "F.Cu" "F.Mask" "F.Paste")
			(net "GPU_3V3IO_RSVD5_FFU")
		)
	)
	(footprint ""
		(layer "F.Cu")
		(at 367.523776 -152.71115 90)
		(property "Reference" "R752"
			(at 0 0 90)
			(layer "F.SilkS")
			(hide yes)
			(effects
				(font
					(size 1.27 1.27)
				)
			)
		)
		(property "Value" ""
			(at 0 0 90)
			(layer "F.Fab")
			(effects
				(font
					(size 1.27 1.27)
				)
			)
		)
		(duplicate_pad_numbers_are_jumpers no)
		(fp_line
			(start 0.7874 -0.4064)
			(end 0.7874 0.4064)
			(stroke
				(width 0.1524)
				(type default)
			)
			(layer "F.SilkS")
		)
		(fp_line
			(start -0.7874 -0.4064)
			(end 0.7874 -0.4064)
			(stroke
				(width 0.1524)
				(type default)
			)
			(layer "F.SilkS")
		)
		(fp_line
			(start 0.7874 0.4064)
			(end -0.7874 0.4064)
			(stroke
				(width 0.1524)
				(type default)
			)
			(layer "F.SilkS")
		)
		(fp_line
			(start -0.7874 0.4064)
			(end -0.7874 -0.4064)
			(stroke
				(width 0.1524)
				(type default)
			)
			(layer "F.SilkS")
		)
		(fp_line
			(start -0.12065 -0.305054)
			(end -0.12065 -0.2794)
			(stroke
				(width 0.1)
				(type default)
			)
			(layer "F.Fab")
		)
		(fp_line
			(start -0.67945 -0.305054)
			(end -0.12065 -0.305054)
			(stroke
				(width 0.1)
				(type default)
			)
			(layer "F.Fab")
		)
		(fp_line
			(start 0.67945 -0.3048)
			(end 0.67945 0.3048)
			(stroke
				(width 0.1)
				(type default)
			)
			(layer "F.Fab")
		)
		(fp_line
			(start 0.12065 -0.3048)
			(end 0.67945 -0.3048)
			(stroke
				(width 0.1)
				(type default)
			)
			(layer "F.Fab")
		)
		(fp_line
			(start 0.12065 -0.2794)
			(end 0.12065 -0.3048)
			(stroke
				(width 0.1)
				(type default)
			)
			(layer "F.Fab")
		)
		(fp_line
			(start -0.12065 -0.2794)
			(end 0.12065 -0.2794)
			(stroke
				(width 0.1)
				(type default)
			)
			(layer "F.Fab")
		)
		(fp_line
			(start 0.120396 0.2794)
			(end -0.12065 0.2794)
			(stroke
				(width 0.1)
				(type default)
			)
			(layer "F.Fab")
		)
		(fp_line
			(start -0.12065 0.2794)
			(end -0.12065 0.3048)
			(stroke
				(width 0.1)
				(type default)
			)
			(layer "F.Fab")
		)
		(fp_line
			(start 0.67945 0.3048)
			(end 0.120396 0.3048)
			(stroke
				(width 0.1)
				(type default)
			)
			(layer "F.Fab")
		)
		(fp_line
			(start 0.120396 0.3048)
			(end 0.120396 0.2794)
			(stroke
				(width 0.1)
				(type default)
			)
			(layer "F.Fab")
		)
		(fp_line
			(start -0.12065 0.3048)
			(end -0.67945 0.3048)
			(stroke
				(width 0.1)
				(type default)
			)
			(layer "F.Fab")
		)
		(fp_line
			(start -0.67945 0.3048)
			(end -0.67945 -0.305054)
			(stroke
				(width 0.1)
				(type default)
			)
			(layer "F.Fab")
		)
		(pad "1" smd circle
			(at -0.40005 0 90)
			(size 0 0)
			(layers "F.Cu" "F.Mask" "F.Paste")
			(net "NIC6_ADC_A0")
		)
		(pad "2" smd circle
			(at 0.40005 0 90)
			(size 0 0)
			(layers "F.Cu" "F.Mask" "F.Paste")
			(net "GND")
		)
	)
	(footprint ""
		(layer "F.Cu")
		(at 450.230494 -120.79224)
		(property "Reference" "R6051"
			(at 0 0 0)
			(layer "F.SilkS")
			(hide yes)
			(effects
				(font
					(size 1.27 1.27)
				)
			)
		)
		(property "Value" ""
			(at 0 0 0)
			(layer "F.Fab")
			(effects
				(font
					(size 1.27 1.27)
				)
			)
		)
		(duplicate_pad_numbers_are_jumpers no)
		(fp_line
			(start -0.7874 -0.4064)
			(end 0.7874 -0.4064)
			(stroke
				(width 0.1524)
				(type default)
			)
			(layer "F.SilkS")
		)
		(fp_line
			(start -0.7874 0.4064)
			(end -0.7874 -0.4064)
			(stroke
				(width 0.1524)
				(type default)
			)
			(layer "F.SilkS")
		)
		(fp_line
			(start 0.7874 -0.4064)
			(end 0.7874 0.4064)
			(stroke
				(width 0.1524)
				(type default)
			)
			(layer "F.SilkS")
		)
		(fp_line
			(start 0.7874 0.4064)
			(end -0.7874 0.4064)
			(stroke
				(width 0.1524)
				(type default)
			)
			(layer "F.SilkS")
		)
		(fp_line
			(start -0.67945 -0.305054)
			(end -0.12065 -0.305054)
			(stroke
				(width 0.1)
				(type default)
			)
			(layer "F.Fab")
		)
		(fp_line
			(start -0.67945 0.3048)
			(end -0.67945 -0.305054)
			(stroke
				(width 0.1)
				(type default)
			)
			(layer "F.Fab")
		)
		(fp_line
			(start -0.12065 -0.305054)
			(end -0.12065 -0.2794)
			(stroke
				(width 0.1)
				(type default)
			)
			(layer "F.Fab")
		)
		(fp_line
			(start -0.12065 -0.2794)
			(end 0.12065 -0.2794)
			(stroke
				(width 0.1)
				(type default)
			)
			(layer "F.Fab")
		)
		(fp_line
			(start -0.12065 0.2794)
			(end -0.12065 0.3048)
			(stroke
				(width 0.1)
				(type default)
			)
			(layer "F.Fab")
		)
		(fp_line
			(start -0.12065 0.3048)
			(end -0.67945 0.3048)
			(stroke
				(width 0.1)
				(type default)
			)
			(layer "F.Fab")
		)
		(fp_line
			(start 0.120396 0.2794)
			(end -0.12065 0.2794)
			(stroke
				(width 0.1)
				(type default)
			)
			(layer "F.Fab")
		)
		(fp_line
			(start 0.120396 0.3048)
			(end 0.120396 0.2794)
			(stroke
				(width 0.1)
				(type default)
			)
			(layer "F.Fab")
		)
		(fp_line
			(start 0.12065 -0.3048)
			(end 0.67945 -0.3048)
			(stroke
				(width 0.1)
				(type default)
			)
			(layer "F.Fab")
		)
		(fp_line
			(start 0.12065 -0.2794)
			(end 0.12065 -0.3048)
			(stroke
				(width 0.1)
				(type default)
			)
			(layer "F.Fab")
		)
		(fp_line
			(start 0.67945 -0.3048)
			(end 0.67945 0.3048)
			(stroke
				(width 0.1)
				(type default)
			)
			(layer "F.Fab")
		)
		(fp_line
			(start 0.67945 0.3048)
			(end 0.120396 0.3048)
			(stroke
				(width 0.1)
				(type default)
			)
			(layer "F.Fab")
		)
		(pad "1" smd circle
			(at -0.40005 0)
			(size 0 0)
			(layers "F.Cu" "F.Mask" "F.Paste")
			(net "P3V3_NIC7")
		)
		(pad "2" smd circle
			(at 0.40005 0)
			(size 0 0)
			(layers "F.Cu" "F.Mask" "F.Paste")
			(net "P3V3_NIC7_PG_G1")
		)
	)
	(footprint ""
		(layer "F.Cu")
		(at 336.042 -160.782 180)
		(property "Reference" "R4811"
			(at 0 0 180)
			(layer "F.SilkS")
			(hide yes)
			(effects
				(font
					(size 1.27 1.27)
				)
			)
		)
		(property "Value" ""
			(at 0 0 180)
			(layer "F.Fab")
			(effects
				(font
					(size 1.27 1.27)
				)
			)
		)
		(duplicate_pad_numbers_are_jumpers no)
		(fp_line
			(start 0.7874 0.4064)
			(end -0.7874 0.4064)
			(stroke
				(width 0.1524)
				(type default)
			)
			(layer "F.SilkS")
		)
		(fp_line
			(start 0.7874 -0.4064)
			(end 0.7874 0.4064)
			(stroke
				(width 0.1524)
				(type default)
			)
			(layer "F.SilkS")
		)
		(fp_line
			(start -0.7874 0.4064)
			(end -0.7874 -0.4064)
			(stroke
				(width 0.1524)
				(type default)
			)
			(layer "F.SilkS")
		)
		(fp_line
			(start -0.7874 -0.4064)
			(end 0.7874 -0.4064)
			(stroke
				(width 0.1524)
				(type default)
			)
			(layer "F.SilkS")
		)
		(fp_line
			(start 0.67945 0.3048)
			(end 0.120396 0.3048)
			(stroke
				(width 0.1)
				(type default)
			)
			(layer "F.Fab")
		)
		(fp_line
			(start 0.67945 -0.3048)
			(end 0.67945 0.3048)
			(stroke
				(width 0.1)
				(type default)
			)
			(layer "F.Fab")
		)
		(fp_line
			(start 0.12065 -0.2794)
			(end 0.12065 -0.3048)
			(stroke
				(width 0.1)
				(type default)
			)
			(layer "F.Fab")
		)
		(fp_line
			(start 0.12065 -0.3048)
			(end 0.67945 -0.3048)
			(stroke
				(width 0.1)
				(type default)
			)
			(layer "F.Fab")
		)
		(fp_line
			(start 0.120396 0.3048)
			(end 0.120396 0.2794)
			(stroke
				(width 0.1)
				(type default)
			)
			(layer "F.Fab")
		)
		(fp_line
			(start 0.120396 0.2794)
			(end -0.12065 0.2794)
			(stroke
				(width 0.1)
				(type default)
			)
			(layer "F.Fab")
		)
		(fp_line
			(start -0.12065 0.3048)
			(end -0.67945 0.3048)
			(stroke
				(width 0.1)
				(type default)
			)
			(layer "F.Fab")
		)
		(fp_line
			(start -0.12065 0.2794)
			(end -0.12065 0.3048)
			(stroke
				(width 0.1)
				(type default)
			)
			(layer "F.Fab")
		)
		(fp_line
			(start -0.12065 -0.2794)
			(end 0.12065 -0.2794)
			(stroke
				(width 0.1)
				(type default)
			)
			(layer "F.Fab")
		)
		(fp_line
			(start -0.12065 -0.305054)
			(end -0.12065 -0.2794)
			(stroke
				(width 0.1)
				(type default)
			)
			(layer "F.Fab")
		)
		(fp_line
			(start -0.67945 0.3048)
			(end -0.67945 -0.305054)
			(stroke
				(width 0.1)
				(type default)
			)
			(layer "F.Fab")
		)
		(fp_line
			(start -0.67945 -0.305054)
			(end -0.12065 -0.305054)
			(stroke
				(width 0.1)
				(type default)
			)
			(layer "F.Fab")
		)
		(pad "1" smd circle
			(at -0.40005 0 180)
			(size 0 0)
			(layers "F.Cu" "F.Mask" "F.Paste")
			(net "PCA9555_0_PEX3_A2")
		)
		(pad "2" smd circle
			(at 0.40005 0 180)
			(size 0 0)
			(layers "F.Cu" "F.Mask" "F.Paste")
			(net "P3V3_AUX")
		)
	)
	(footprint ""
		(layer "F.Cu")
		(at 328.936604 -343.952322 90)
		(property "Reference" "C536"
			(at 0 0 90)
			(layer "F.SilkS")
			(hide yes)
			(effects
				(font
					(size 1.27 1.27)
				)
			)
		)
		(property "Value" ""
			(at 0 0 90)
			(layer "F.Fab")
			(effects
				(font
					(size 1.27 1.27)
				)
			)
		)
		(duplicate_pad_numbers_are_jumpers no)
		(fp_line
			(start 0.299974 -0.150114)
			(end 0.299974 0.150114)
			(stroke
				(width 0.1)
				(type default)
			)
			(layer "F.Fab")
		)
		(fp_line
			(start -0.299974 -0.150114)
			(end 0.299974 -0.150114)
			(stroke
				(width 0.1)
				(type default)
			)
			(layer "F.Fab")
		)
		(fp_line
			(start 0.299974 0.150114)
			(end -0.299974 0.150114)
			(stroke
				(width 0.1)
				(type default)
			)
			(layer "F.Fab")
		)
		(fp_line
			(start -0.299974 0.150114)
			(end -0.299974 -0.150114)
			(stroke
				(width 0.1)
				(type default)
			)
			(layer "F.Fab")
		)
		(pad "1" smd rect
			(at -0.2667 0 90)
			(size 0.3048 0.381)
			(layers "F.Cu" "F.Mask" "F.Paste")
			(net "P5E_PEX2_STN5_TX_DN<87>")
		)
		(pad "2" smd rect
			(at 0.2667 0 90)
			(size 0.3048 0.381)
			(layers "F.Cu" "F.Mask" "F.Paste")
			(net "P5E_PEX2_STN5_TX_C_DN<87>")
		)
	)
)
